# BASEBOARD_FAB2 (Tioga Pass) — schematic netlist excerpt (pin names and nets, part order shuffled) for the footprints in the layout excerpt that follows; sources: Cadence DE-HDL packaged netlist, KiCad conversion of Wiwynn_Tioga_Pass_MB.brd

C6B13  CAP  0.22UF 16V 10% X7R  pkg 0402  page 105 : A = P3E_CPU0_PE1_PCH_TXP<11> ; B = P3E_CPU0_PE1_PCH_C_TXP<11>
R8D24  RES  20.0 1% CHIP  pkg 0402  page 167 : A = SMB_SENSOR_STBY_LVC3_SCL ; B = SMB_SENSOR_STBY_LVC3_SCL_R2
R8E31  RES  23.2K 1% CHIP  pkg 0402  page 240 : A = VSENSE_P3V3_STBY ; B = VSENSE_VOUT_P3V3_STBY

(kicad_pcb
	(version 20260206)
	(generator "pcbnew")
	(generator_version "10.0")
	(general
		(thickness 1.6)
		(legacy_teardrops no)
	)
	(paper "A4")
	(title_block
		(title "Wiwynn_Tioga_Pass_MB.brd")
		(comment 1 "Tioga Pass / footprints 1142-1144 of 4770")
	)
	(layers
		(0 "F.Cu" signal "TOP")
		(4 "In1.Cu" signal "L2GND")
		(6 "In2.Cu" signal "L3")
		(8 "In3.Cu" signal "L4GND")
		(10 "In4.Cu" signal "L5")
		(12 "In5.Cu" signal "L6GND")
		(14 "In6.Cu" signal "L7VCC")
		(16 "In7.Cu" signal "L8VCC")
		(18 "In8.Cu" signal "L9GND")
		(20 "In9.Cu" signal "L10")
		(22 "In10.Cu" signal "L11GND")
		(24 "In11.Cu" signal "L12")
		(26 "In12.Cu" signal "L13GND")
		(2 "B.Cu" signal "BOTTOM")
		(9 "F.Adhes" user "F.Adhesive")
		(11 "B.Adhes" user "B.Adhesive")
		(13 "F.Paste" user "Package Geometry/Pastemask Top")
		(15 "B.Paste" user "Package Geometry/Pastemask Bottom")
		(5 "F.SilkS" user "Ref Des/Silkscreen Top")
		(7 "B.SilkS" user "Ref Des/Silkscreen Bottom")
		(1 "F.Mask" user "Board Geometry/Soldermask Top")
		(3 "B.Mask" user "Board Geometry/Soldermask Bottom")
		(17 "Dwgs.User" user "User.Drawings")
		(19 "Cmts.User" user "User.Comments")
		(21 "Eco1.User" user "User.Eco1")
		(23 "Eco2.User" user "User.Eco2")
		(25 "Edge.Cuts" user "Board Geometry/Outline")
		(27 "Margin" user)
		(31 "F.CrtYd" user "Package Geometry/Place Bound Top")
		(29 "B.CrtYd" user "Package Geometry/Place Bound Bottom")
		(35 "F.Fab" user "Ref Des/Assembly Top")
		(33 "B.Fab" user "Ref Des/Assembly Bottom")
	)
	(footprint ""
		(layer "F.Cu")
		(at 411.115256 -56.50484 -90)
		(property "Reference" "R8D24"
			(at 0 0 270)
			(layer "F.SilkS")
			(hide yes)
			(effects
				(font
					(size 1.27 1.27)
				)
			)
		)
		(property "Value" ""
			(at 0 0 270)
			(layer "F.Fab")
			(effects
				(font
					(size 1.27 1.27)
				)
			)
		)
		(duplicate_pad_numbers_are_jumpers no)
		(fp_poly
			(pts
				(xy -0.2794 -0.1016) (xy 0.2794 -0.1016) (xy 0.2794 0.9906) (xy -0.2794 0.9906)
			)
			(stroke
				(width 0)
				(type default)
			)
			(fill no)
			(layer "F.CrtYd")
		)
		(fp_line
			(start -0.2794 0.9906)
			(end 0.2794 0.9906)
			(stroke
				(width 0.1)
				(type default)
			)
			(layer "F.Fab")
		)
		(fp_line
			(start 0.2794 0.9906)
			(end 0.2794 -0.1016)
			(stroke
				(width 0.1)
				(type default)
			)
			(layer "F.Fab")
		)
		(fp_line
			(start -0.2794 -0.1016)
			(end -0.2794 0.9906)
			(stroke
				(width 0.1)
				(type default)
			)
			(layer "F.Fab")
		)
		(fp_line
			(start 0.2794 -0.1016)
			(end -0.2794 -0.1016)
			(stroke
				(width 0.1)
				(type default)
			)
			(layer "F.Fab")
		)
		(pad "1" smd rect
			(at 0 0 270)
			(size 0.508 0.508)
			(layers "F.Cu" "F.Mask" "F.Paste")
			(net "SMB_SENSOR_STBY_LVC3_SCL")
		)
		(pad "2" smd rect
			(at 0 0.889 270)
			(size 0.508 0.508)
			(layers "F.Cu" "F.Mask" "F.Paste")
			(net "SMB_SENSOR_STBY_LVC3_SCL_R2")
		)
		(zone
			(layer "F.Cu")
			(hatch none 0.5)
			(connect_pads
				(clearance 0)
			)
			(min_thickness 0.25)
			(keepout
				(tracks not_allowed)
				(vias allowed)
				(pads allowed)
				(copperpour not_allowed)
				(footprints allowed)
			)
			(placement
				(enabled no)
				(sheetname "")
			)
			(fill
				(thermal_gap 0.5)
				(thermal_bridge_width 0.5)
				(island_removal_mode 0)
			)
			(polygon
				(pts
					(xy 410.480256 -56.75884) (xy 410.480256 -56.25084) (xy 410.861256 -56.25084) (xy 410.861256 -56.75884)
				)
			)
		)
		(zone
			(layer "F.Cu")
			(hatch none 0.5)
			(connect_pads
				(clearance 0)
			)
			(min_thickness 0.25)
			(keepout
				(tracks allowed)
				(vias not_allowed)
				(pads allowed)
				(copperpour not_allowed)
				(footprints allowed)
			)
			(placement
				(enabled no)
				(sheetname "")
			)
			(fill
				(thermal_gap 0.5)
				(thermal_bridge_width 0.5)
				(island_removal_mode 0)
			)
			(polygon
				(pts
					(xy 410.861256 -56.75884) (xy 410.861256 -56.25084) (xy 410.480256 -56.25084) (xy 410.480256 -56.75884)
				)
			)
		)
	)
	(footprint ""
		(layer "F.Cu")
		(at 467.257892 -26.665936)
		(property "Reference" "R8E31"
			(at 0 0 0)
			(layer "F.SilkS")
			(hide yes)
			(effects
				(font
					(size 1.27 1.27)
				)
			)
		)
		(property "Value" ""
			(at 0 0 0)
			(layer "F.Fab")
			(effects
				(font
					(size 1.27 1.27)
				)
			)
		)
		(duplicate_pad_numbers_are_jumpers no)
		(fp_rect
			(start -0.2794 0.9906)
			(end 0.2794 -0.1016)
			(stroke
				(width 0)
				(type default)
			)
			(fill no)
			(layer "F.CrtYd")
		)
		(fp_line
			(start -0.2794 -0.1016)
			(end -0.2794 0.9906)
			(stroke
				(width 0.1)
				(type default)
			)
			(layer "F.Fab")
		)
		(fp_line
			(start -0.2794 0.9906)
			(end 0.2794 0.9906)
			(stroke
				(width 0.1)
				(type default)
			)
			(layer "F.Fab")
		)
		(fp_line
			(start 0.2794 -0.1016)
			(end -0.2794 -0.1016)
			(stroke
				(width 0.1)
				(type default)
			)
			(layer "F.Fab")
		)
		(fp_line
			(start 0.2794 0.9906)
			(end 0.2794 -0.1016)
			(stroke
				(width 0.1)
				(type default)
			)
			(layer "F.Fab")
		)
		(pad "1" smd rect
			(at 0 0)
			(size 0.508 0.508)
			(layers "F.Cu" "F.Mask" "F.Paste")
			(net "VSENSE_P3V3_STBY")
		)
		(pad "2" smd rect
			(at 0 0.889)
			(size 0.508 0.508)
			(layers "F.Cu" "F.Mask" "F.Paste")
			(net "VSENSE_VOUT_P3V3_STBY")
		)
		(zone
			(layer "F.Cu")
			(hatch none 0.5)
			(connect_pads
				(clearance 0)
			)
			(min_thickness 0.25)
			(keepout
				(tracks allowed)
				(vias not_allowed)
				(pads allowed)
				(copperpour not_allowed)
				(footprints allowed)
			)
			(placement
				(enabled no)
				(sheetname "")
			)
			(fill
				(thermal_gap 0.5)
				(thermal_bridge_width 0.5)
				(island_removal_mode 0)
			)
			(polygon
				(pts
					(xy 467.003892 -26.030936) (xy 467.511892 -26.030936) (xy 467.511892 -26.411936) (xy 467.003892 -26.411936)
				)
			)
		)
		(zone
			(layer "F.Cu")
			(hatch none 0.5)
			(connect_pads
				(clearance 0)
			)
			(min_thickness 0.25)
			(keepout
				(tracks not_allowed)
				(vias allowed)
				(pads allowed)
				(copperpour not_allowed)
				(footprints allowed)
			)
			(placement
				(enabled no)
				(sheetname "")
			)
			(fill
				(thermal_gap 0.5)
				(thermal_bridge_width 0.5)
				(island_removal_mode 0)
			)
			(polygon
				(pts
					(xy 467.003892 -26.030936) (xy 467.511892 -26.030936) (xy 467.511892 -26.411936) (xy 467.003892 -26.411936)
				)
			)
		)
	)
	(footprint ""
		(layer "F.Cu")
		(at 323.0245 -118.415816 90)
		(property "Reference" "C6B13"
			(at -0.8382 -0.67818 90)
			(unlocked yes)
			(layer "F.SilkS")
			(effects
				(font
					(size 0.4064 0.254)
					(thickness 0.1524)
				)
				(justify left)
			)
		)
		(property "Value" ""
			(at 0 0 90)
			(layer "F.Fab")
			(effects
				(font
					(size 1.27 1.27)
				)
			)
		)
		(duplicate_pad_numbers_are_jumpers no)
		(fp_poly
			(pts
				(xy 0.3048 -0.1016) (xy 0.3048 0.9906) (xy -0.3048 0.9906) (xy -0.3048 -0.1016)
			)
			(stroke
				(width 0)
				(type default)
			)
			(fill no)
			(layer "F.CrtYd")
		)
		(fp_line
			(start 0.3048 -0.1016)
			(end -0.3048 -0.1016)
			(stroke
				(width 0.1)
				(type default)
			)
			(layer "F.Fab")
		)
		(fp_line
			(start -0.3048 -0.1016)
			(end -0.3048 0.9906)
			(stroke
				(width 0.1)
				(type default)
			)
			(layer "F.Fab")
		)
		(fp_line
			(start 0.3048 0.9906)
			(end 0.3048 -0.1016)
			(stroke
				(width 0.1)
				(type default)
			)
			(layer "F.Fab")
		)
		(fp_line
			(start -0.3048 0.9906)
			(end 0.3048 0.9906)
			(stroke
				(width 0.1)
				(type default)
			)
			(layer "F.Fab")
		)
		(pad "1" smd rect
			(at 0 0 90)
			(size 0.508 0.508)
			(layers "F.Cu" "F.Mask" "F.Paste")
			(net "P3E_CPU0_PE1_PCH_TXP<11>")
		)
		(pad "2" smd rect
			(at 0 0.889 90)
			(size 0.508 0.508)
			(layers "F.Cu" "F.Mask" "F.Paste")
			(net "P3E_CPU0_PE1_PCH_C_TXP<11>")
		)
		(zone
			(layer "F.Cu")
			(hatch none 0.5)
			(connect_pads
				(clearance 0)
			)
			(min_thickness 0.25)
			(keepout
				(tracks allowed)
				(vias not_allowed)
				(pads allowed)
				(copperpour not_allowed)
				(footprints allowed)
			)
			(placement
				(enabled no)
				(sheetname "")
			)
			(fill
				(thermal_gap 0.5)
				(thermal_bridge_width 0.5)
				(island_removal_mode 0)
			)
			(polygon
				(pts
					(xy 323.2785 -118.161816) (xy 323.2785 -118.669816) (xy 323.6595 -118.669816) (xy 323.6595 -118.161816)
				)
			)
		)
		(zone
			(layer "F.Cu")
			(hatch none 0.5)
			(connect_pads
				(clearance 0)
			)
			(min_thickness 0.25)
			(keepout
				(tracks not_allowed)
				(vias allowed)
				(pads allowed)
				(copperpour not_allowed)
				(footprints allowed)
			)
			(placement
				(enabled no)
				(sheetname "")
			)
			(fill
				(thermal_gap 0.5)
				(thermal_bridge_width 0.5)
				(island_removal_mode 0)
			)
			(polygon
				(pts
					(xy 323.6595 -118.161816) (xy 323.6595 -118.669816) (xy 323.2785 -118.669816) (xy 323.2785 -118.161816)
				)
			)
		)
	)
)
